# SCM (Grand Teton) — schematic netlist excerpt (pin names and nets, part order shuffled) for the footprints in the layout excerpt that follows; sources: Cadence DE-HDL packaged netlist, KiCad conversion of 12092022_DA0F0TMDCD0_F0T_Management_Board_D_brd_V3_OCP.brd

R20  Q_RES  0 5% CHIP  pkg 0402LF  page 15 : A = V_VGAVS_R ; B = V_VGAVS
R705  Q_RES  33.2 1% CHIP  pkg 0402LF  page 12 : A = FM_BMC_DBP_PRESENT_N ; B = FM_BMC_DBP_PRESENT_R_N

(kicad_pcb
	(version 20260206)
	(generator "pcbnew")
	(generator_version "10.0")
	(general
		(thickness 1.6)
		(legacy_teardrops no)
	)
	(paper "A4")
	(title_block
		(title "12092022_DA0F0TMDCD0_F0T_Management_Board_D_brd_V3_OCP.brd")
		(comment 1 "Grand Teton / footprints 511-512 of 1440")
	)
	(layers
		(0 "F.Cu" signal "TOP")
		(4 "In1.Cu" signal "GND")
		(6 "In2.Cu" signal "IN1")
		(8 "In3.Cu" signal "GND1")
		(10 "In4.Cu" signal "IN2")
		(12 "In5.Cu" signal "VCC")
		(14 "In6.Cu" signal "VCC1")
		(16 "In7.Cu" signal "IN3")
		(18 "In8.Cu" signal "GND2")
		(20 "In9.Cu" signal "IN4")
		(22 "In10.Cu" signal "GND3")
		(2 "B.Cu" signal "BOTTOM")
		(9 "F.Adhes" user "F.Adhesive")
		(11 "B.Adhes" user "B.Adhesive")
		(13 "F.Paste" user "Package Geometry/Pastemask Top")
		(15 "B.Paste" user "Package Geometry/Pastemask Bottom")
		(5 "F.SilkS" user "Ref Des/Silkscreen Top")
		(7 "B.SilkS" user "Ref Des/Silkscreen Bottom")
		(1 "F.Mask" user "Board Geometry/Soldermask Top")
		(3 "B.Mask" user "Board Geometry/Soldermask Bottom")
		(17 "Dwgs.User" user "User.Drawings")
		(19 "Cmts.User" user "User.Comments")
		(21 "Eco1.User" user "User.Eco1")
		(23 "Eco2.User" user "User.Eco2")
		(25 "Edge.Cuts" user "Board Geometry/Outline")
		(27 "Margin" user)
		(31 "F.CrtYd" user "Package Geometry/Place Bound Top")
		(29 "B.CrtYd" user "Package Geometry/Place Bound Bottom")
		(35 "F.Fab" user "Ref Des/Assembly Top")
		(33 "B.Fab" user "Ref Des/Assembly Bottom")
	)
	(footprint ""
		(layer "F.Cu")
		(at 45.72 -34.6202 90)
		(property "Reference" "R705"
			(at 0 0 90)
			(layer "F.SilkS")
			(hide yes)
			(effects
				(font
					(size 1.27 1.27)
				)
			)
		)
		(property "Value" ""
			(at 0 0 90)
			(layer "F.Fab")
			(effects
				(font
					(size 1.27 1.27)
				)
			)
		)
		(duplicate_pad_numbers_are_jumpers no)
		(fp_line
			(start 0.7874 -0.4064)
			(end 0.7874 0.4064)
			(stroke
				(width 0.1524)
				(type default)
			)
			(layer "F.SilkS")
		)
		(fp_line
			(start -0.7874 -0.4064)
			(end 0.7874 -0.4064)
			(stroke
				(width 0.1524)
				(type default)
			)
			(layer "F.SilkS")
		)
		(fp_line
			(start 0.7874 0.4064)
			(end -0.7874 0.4064)
			(stroke
				(width 0.1524)
				(type default)
			)
			(layer "F.SilkS")
		)
		(fp_line
			(start -0.7874 0.4064)
			(end -0.7874 -0.4064)
			(stroke
				(width 0.1524)
				(type default)
			)
			(layer "F.SilkS")
		)
		(fp_line
			(start -0.12065 -0.305054)
			(end -0.12065 -0.2794)
			(stroke
				(width 0.1)
				(type default)
			)
			(layer "F.Fab")
		)
		(fp_line
			(start -0.67945 -0.305054)
			(end -0.12065 -0.305054)
			(stroke
				(width 0.1)
				(type default)
			)
			(layer "F.Fab")
		)
		(fp_line
			(start 0.67945 -0.3048)
			(end 0.67945 0.3048)
			(stroke
				(width 0.1)
				(type default)
			)
			(layer "F.Fab")
		)
		(fp_line
			(start 0.12065 -0.3048)
			(end 0.67945 -0.3048)
			(stroke
				(width 0.1)
				(type default)
			)
			(layer "F.Fab")
		)
		(fp_line
			(start 0.12065 -0.2794)
			(end 0.12065 -0.3048)
			(stroke
				(width 0.1)
				(type default)
			)
			(layer "F.Fab")
		)
		(fp_line
			(start -0.12065 -0.2794)
			(end 0.12065 -0.2794)
			(stroke
				(width 0.1)
				(type default)
			)
			(layer "F.Fab")
		)
		(fp_line
			(start 0.120396 0.2794)
			(end -0.12065 0.2794)
			(stroke
				(width 0.1)
				(type default)
			)
			(layer "F.Fab")
		)
		(fp_line
			(start -0.12065 0.2794)
			(end -0.12065 0.3048)
			(stroke
				(width 0.1)
				(type default)
			)
			(layer "F.Fab")
		)
		(fp_line
			(start 0.67945 0.3048)
			(end 0.120396 0.3048)
			(stroke
				(width 0.1)
				(type default)
			)
			(layer "F.Fab")
		)
		(fp_line
			(start 0.120396 0.3048)
			(end 0.120396 0.2794)
			(stroke
				(width 0.1)
				(type default)
			)
			(layer "F.Fab")
		)
		(fp_line
			(start -0.12065 0.3048)
			(end -0.67945 0.3048)
			(stroke
				(width 0.1)
				(type default)
			)
			(layer "F.Fab")
		)
		(fp_line
			(start -0.67945 0.3048)
			(end -0.67945 -0.305054)
			(stroke
				(width 0.1)
				(type default)
			)
			(layer "F.Fab")
		)
		(pad "1" smd circle
			(at -0.40005 0 90)
			(size 0 0)
			(layers "F.Cu" "F.Mask" "F.Paste")
			(net "FM_BMC_DBP_PRESENT_N")
		)
		(pad "2" smd circle
			(at 0.40005 0 90)
			(size 0 0)
			(layers "F.Cu" "F.Mask" "F.Paste")
			(net "FM_BMC_DBP_PRESENT_R_N")
		)
	)
	(footprint ""
		(layer "F.Cu")
		(at 54.040278 -34.637726 -90)
		(property "Reference" "R20"
			(at 0 0 270)
			(layer "F.SilkS")
			(hide yes)
			(effects
				(font
					(size 1.27 1.27)
				)
			)
		)
		(property "Value" ""
			(at 0 0 270)
			(layer "F.Fab")
			(effects
				(font
					(size 1.27 1.27)
				)
			)
		)
		(duplicate_pad_numbers_are_jumpers no)
		(fp_line
			(start -0.7874 0.4064)
			(end -0.7874 -0.4064)
			(stroke
				(width 0.1524)
				(type default)
			)
			(layer "F.SilkS")
		)
		(fp_line
			(start 0.7874 0.4064)
			(end -0.7874 0.4064)
			(stroke
				(width 0.1524)
				(type default)
			)
			(layer "F.SilkS")
		)
		(fp_line
			(start -0.7874 -0.4064)
			(end 0.7874 -0.4064)
			(stroke
				(width 0.1524)
				(type default)
			)
			(layer "F.SilkS")
		)
		(fp_line
			(start 0.7874 -0.4064)
			(end 0.7874 0.4064)
			(stroke
				(width 0.1524)
				(type default)
			)
			(layer "F.SilkS")
		)
		(fp_line
			(start -0.67945 0.3048)
			(end -0.67945 -0.305054)
			(stroke
				(width 0.1)
				(type default)
			)
			(layer "F.Fab")
		)
		(fp_line
			(start -0.12065 0.3048)
			(end -0.67945 0.3048)
			(stroke
				(width 0.1)
				(type default)
			)
			(layer "F.Fab")
		)
		(fp_line
			(start 0.120396 0.3048)
			(end 0.120396 0.2794)
			(stroke
				(width 0.1)
				(type default)
			)
			(layer "F.Fab")
		)
		(fp_line
			(start 0.67945 0.3048)
			(end 0.120396 0.3048)
			(stroke
				(width 0.1)
				(type default)
			)
			(layer "F.Fab")
		)
		(fp_line
			(start -0.12065 0.2794)
			(end -0.12065 0.3048)
			(stroke
				(width 0.1)
				(type default)
			)
			(layer "F.Fab")
		)
		(fp_line
			(start 0.120396 0.2794)
			(end -0.12065 0.2794)
			(stroke
				(width 0.1)
				(type default)
			)
			(layer "F.Fab")
		)
		(fp_line
			(start -0.12065 -0.2794)
			(end 0.12065 -0.2794)
			(stroke
				(width 0.1)
				(type default)
			)
			(layer "F.Fab")
		)
		(fp_line
			(start 0.12065 -0.2794)
			(end 0.12065 -0.3048)
			(stroke
				(width 0.1)
				(type default)
			)
			(layer "F.Fab")
		)
		(fp_line
			(start 0.12065 -0.3048)
			(end 0.67945 -0.3048)
			(stroke
				(width 0.1)
				(type default)
			)
			(layer "F.Fab")
		)
		(fp_line
			(start 0.67945 -0.3048)
			(end 0.67945 0.3048)
			(stroke
				(width 0.1)
				(type default)
			)
			(layer "F.Fab")
		)
		(fp_line
			(start -0.67945 -0.305054)
			(end -0.12065 -0.305054)
			(stroke
				(width 0.1)
				(type default)
			)
			(layer "F.Fab")
		)
		(fp_line
			(start -0.12065 -0.305054)
			(end -0.12065 -0.2794)
			(stroke
				(width 0.1)
				(type default)
			)
			(layer "F.Fab")
		)
		(pad "1" smd circle
			(at -0.40005 0 270)
			(size 0 0)
			(layers "F.Cu" "F.Mask" "F.Paste")
			(net "V_VGAVS_R")
		)
		(pad "2" smd circle
			(at 0.40005 0 270)
			(size 0 0)
			(layers "F.Cu" "F.Mask" "F.Paste")
			(net "V_VGAVS")
		)
	)
)
